FILE_TYPE = MACRO_DRAWING;
SET COLOR_WIRE YELLOW;
SET COLOR_PROP ORANGE;
SET COLOR_DOT WHITE;
SET COLOR_ARC YELLOW;
SET COLOR_BODY GREEN;
SET COLOR_NOTE PURPLE;
SET PROP_DISPLAY VALUE;
SET PAGE_NUMBER P424;
FORCEADD QUANTA_TITLE_BLOCK_C..1
(0 0);
FORCEPROP 1 LAST CUSTOM_TXT_CDS <NAME_2>
J 0
(-3175 50);
FORCEPROP 1 LAST CUSTOM_TXT_CDS <NAME_1>
J 0
(-3175 175);
FORCEPROP 1 LAST CUSTOM_TXT_CDS <Q_NUMBER>
J 0
(-1403 103);
DISPLAY 1.212766 (-1403 103);
FORCEPROP 1 LAST CUSTOM_TXT_CDS <Q_PROJ>
J 0
(-2382 102);
DISPLAY 1.212766 (-2382 102);
FORCEPROP 1 LAST CUSTOM_TXT_CDS <Q_REV>
J 0
(-184 103);
DISPLAY 1.212766 (-184 103);
FORCEPROP 1 LAST CUSTOM_TXT_CDS <CON_LAST_MODIFIED>
J 0
(-1885 15);
DISPLAY 0.978723 (-1885 15);
FORCEPROP 1 LAST CUSTOM_TXT_CDS <CON_PAGE_NUM> OF <CON_TOTAL_PAGES>
J 0
(-446 18);
DISPLAY 0.978723 (-446 18);
FORCEPROP 1 LAST Q_TITLE RETIMER_CPU0_P2(10)
J 0
(-9366 26);
DISPLAY 2.446809 (-9366 26);
PAINT GREEN (-9366 26);
FORCEPROP 2 LAST CDS_LIB pure_quanta
J 0
(0 0);
DISPLAY INVISIBLE (0 0);
FORCEPROP 1 LAST CDS_LMAN_SYM_OUTLINE -9475,6775,100,-125
J 0
(0 0);
DISPLAY 0.468085 (0 0);
PAINT GREEN (0 0);
DISPLAY INVISIBLE (0 0);
FORCEPROP 2 LAST PAGE_BORDER TRUE
J 0
(-7890 5250);
DISPLAY 0.638298 (-7890 5250);
PAINT PINK (-7890 5250);
DISPLAY INVISIBLE (-7890 5250);
FORCEPROP 2 LAST CDS_XR_PAGE_TITLE CR-304 : @T6G_MB_LIB.T6G(SCH_1):PAGE304
J 0
(-7890 5250);
DISPLAY 0.638298 (-7890 5250);
PAINT PINK (-7890 5250);
DISPLAY INVISIBLE (-7890 5250);
FORCEPROP 2 LAST CUSTOM_TXT_CDS <XR_PAGE_TITLE>
J 0
(-7890 5250);
DISPLAY 0.638298 (-7890 5250);
PAINT PINK (-7890 5250);
DISPLAY INVISIBLE (-7890 5250);
FORCEPROP 1 LAST COMMENT_BODY TRUE
J 0
(12 -13);
DISPLAY 0.978723 (12 -13);
PAINT GREEN (12 -13);
DISPLAY INVISIBLE (12 -13);
FORCEPROP 1 LAST Q_DEPT BU9
J 1
(-3763 49);
DISPLAY 1.957447 (-3763 49);
PAINT GREEN (-3763 49);
DISPLAY INVISIBLE (-3763 49);
FORCEPROP 0 LAST CDS_CON_LAST_MODIFIED Thu Aug 24 10:16:27 2023
J 0
(-1885 15);
DISPLAY INVISIBLE (-1885 15);
QUIT
